(kicad_pcb
	(version 20260206)
	(generator "pcbnew")
	(generator_version "10.0")
	(general
		(thickness 1.6)
		(legacy_teardrops no)
	)
	(paper "A4")
	(title_block
		(title "12092022_DA0F0TFB6D0_F0T_FAN_BOARD_MP5048_D_brd_v02_OCP.brd")
		(comment 1 "Grand Teton / footprints 860-861 of 924")
	)
	(layers
		(0 "F.Cu" signal "TOP")
		(4 "In1.Cu" signal "GND")
		(6 "In2.Cu" signal "IN1")
		(8 "In3.Cu" signal "IN2")
		(10 "In4.Cu" signal "GND1")
		(2 "B.Cu" signal "BOTTOM")
		(9 "F.Adhes" user "F.Adhesive")
		(11 "B.Adhes" user "B.Adhesive")
		(13 "F.Paste" user "Package Geometry/Pastemask Top")
		(15 "B.Paste" user "Package Geometry/Pastemask Bottom")
		(5 "F.SilkS" user "Ref Des/Silkscreen Top")
		(7 "B.SilkS" user "Ref Des/Silkscreen Bottom")
		(1 "F.Mask" user "Board Geometry/Soldermask Top")
		(3 "B.Mask" user "Board Geometry/Soldermask Bottom")
		(17 "Dwgs.User" user "User.Drawings")
		(19 "Cmts.User" user "User.Comments")
		(21 "Eco1.User" user "User.Eco1")
		(23 "Eco2.User" user "User.Eco2")
		(25 "Edge.Cuts" user "Board Geometry/Outline")
		(27 "Margin" user)
		(31 "F.CrtYd" user "Package Geometry/Place Bound Top")
		(29 "B.CrtYd" user "Package Geometry/Place Bound Bottom")
		(35 "F.Fab" user "Ref Des/Assembly Top")
		(33 "B.Fab" user "Ref Des/Assembly Bottom")
	)
	(footprint ""
		(layer "B.Cu")
		(at 27.120088 -10.999978)
		(property "Reference" "GF1"
			(at 6.661912 -2.054352 0)
			(unlocked yes)
			(layer "B.SilkS")
			(effects
				(font
					(size 0.7874 0.5842)
					(thickness 0.1524)
				)
				(justify left mirror)
			)
		)
		(property "Value" ""
			(at 0 0 0)
			(layer "B.Fab")
			(effects
				(font
					(size 1.27 1.27)
				)
				(justify mirror)
			)
		)
		(duplicate_pad_numbers_are_jumpers no)
		(fp_line
			(start -8.26008 -0.350012)
			(end -8.26008 9.150096)
			(stroke
				(width 0.1524)
				(type default)
			)
			(layer "F.SilkS")
		)
		(fp_line
			(start -8.26008 9.150096)
			(end -6.759956 10.649966)
			(stroke
				(width 0.1524)
				(type default)
			)
			(layer "F.SilkS")
		)
		(fp_line
			(start -6.759956 10.649966)
			(end -1.849882 10.649966)
			(stroke
				(width 0.1524)
				(type default)
			)
			(layer "F.SilkS")
		)
		(fp_line
			(start -1.849882 10.649966)
			(end -0.350012 9.150096)
			(stroke
				(width 0.1524)
				(type default)
			)
			(layer "F.SilkS")
		)
		(fp_line
			(start -0.350012 9.150096)
			(end -0.350012 0)
			(stroke
				(width 0.1524)
				(type default)
			)
			(layer "F.SilkS")
		)
		(fp_line
			(start 0.350012 0)
			(end 0.350012 2.710688)
			(stroke
				(width 0.1524)
				(type default)
			)
			(layer "F.SilkS")
		)
		(fp_line
			(start 0.514858 9.314942)
			(end 1.849882 10.649966)
			(stroke
				(width 0.1524)
				(type default)
			)
			(layer "F.SilkS")
		)
		(fp_line
			(start 1.849882 10.649966)
			(end 4.219956 10.649966)
			(stroke
				(width 0.1524)
				(type default)
			)
			(layer "F.SilkS")
		)
		(fp_line
			(start 4.219956 10.649966)
			(end 5.72008 9.150096)
			(stroke
				(width 0.1524)
				(type default)
			)
			(layer "F.SilkS")
		)
		(fp_line
			(start 5.72008 -1.149604)
			(end -8.26008 -1.149604)
			(stroke
				(width 0.1524)
				(type default)
			)
			(layer "F.SilkS")
		)
		(fp_line
			(start 5.72008 9.150096)
			(end 5.72008 -0.350012)
			(stroke
				(width 0.1524)
				(type default)
			)
			(layer "F.SilkS")
		)
		(fp_arc
			(start -0.350012 0)
			(mid -0.247504 -0.247514)
			(end 0 -0.350012)
			(stroke
				(width 0.1524)
				(type default)
			)
			(layer "F.SilkS")
		)
		(fp_arc
			(start 0 -0.350012)
			(mid 0.247496 -0.247499)
			(end 0.350012 0)
			(stroke
				(width 0.1524)
				(type default)
			)
			(layer "F.SilkS")
		)
		(fp_line
			(start -8.26008 -0.350012)
			(end -8.26008 9.150096)
			(stroke
				(width 0.1524)
				(type default)
			)
			(layer "B.SilkS")
		)
		(fp_line
			(start -8.26008 9.150096)
			(end -6.759956 10.649966)
			(stroke
				(width 0.1524)
				(type default)
			)
			(layer "B.SilkS")
		)
		(fp_line
			(start -6.759956 10.649966)
			(end -1.849882 10.649966)
			(stroke
				(width 0.1524)
				(type default)
			)
			(layer "B.SilkS")
		)
		(fp_line
			(start -1.849882 10.649966)
			(end -0.350012 9.150096)
			(stroke
				(width 0.1524)
				(type default)
			)
			(layer "B.SilkS")
		)
		(fp_line
			(start -0.350012 9.150096)
			(end -0.350012 0)
			(stroke
				(width 0.1524)
				(type default)
			)
			(layer "B.SilkS")
		)
		(fp_line
			(start 0.350012 0)
			(end 0.350012 2.710688)
			(stroke
				(width 0.1524)
				(type default)
			)
			(layer "B.SilkS")
		)
		(fp_line
			(start 0.514858 9.314942)
			(end 1.849882 10.649966)
			(stroke
				(width 0.1524)
				(type default)
			)
			(layer "B.SilkS")
		)
		(fp_line
			(start 1.849882 10.649966)
			(end 4.219956 10.649966)
			(stroke
				(width 0.1524)
				(type default)
			)
			(layer "B.SilkS")
		)
		(fp_line
			(start 4.219956 10.649966)
			(end 5.72008 9.150096)
			(stroke
				(width 0.1524)
				(type default)
			)
			(layer "B.SilkS")
		)
		(fp_line
			(start 5.72008 -1.149604)
			(end -8.26008 -1.149604)
			(stroke
				(width 0.1524)
				(type default)
			)
			(layer "B.SilkS")
		)
		(fp_line
			(start 5.72008 9.150096)
			(end 5.72008 -0.350012)
			(stroke
				(width 0.1524)
				(type default)
			)
			(layer "B.SilkS")
		)
		(fp_arc
			(start -0.350012 0)
			(mid -0.247504 -0.247514)
			(end 0 -0.350012)
			(stroke
				(width 0.1524)
				(type default)
			)
			(layer "B.SilkS")
		)
		(fp_arc
			(start 0 -0.350012)
			(mid 0.247496 -0.247499)
			(end 0.350012 0)
			(stroke
				(width 0.1524)
				(type default)
			)
			(layer "B.SilkS")
		)
		(fp_line
			(start -8.26008 -0.350012)
			(end -8.26008 9.150096)
			(stroke
				(width 0.1)
				(type default)
			)
			(layer "B.Fab")
		)
		(fp_line
			(start -8.26008 9.150096)
			(end -6.759956 10.649966)
			(stroke
				(width 0.1)
				(type default)
			)
			(layer "B.Fab")
		)
		(fp_line
			(start -6.759956 10.649966)
			(end -1.849882 10.649966)
			(stroke
				(width 0.1)
				(type default)
			)
			(layer "B.Fab")
		)
		(fp_line
			(start -1.849882 10.649966)
			(end -0.350012 9.150096)
			(stroke
				(width 0.1)
				(type default)
			)
			(layer "B.Fab")
		)
		(fp_line
			(start -0.350012 9.150096)
			(end -0.350012 0)
			(stroke
				(width 0.1)
				(type default)
			)
			(layer "B.Fab")
		)
		(fp_line
			(start 0.350012 0)
			(end 0.350012 9.150096)
			(stroke
				(width 0.1)
				(type default)
			)
			(layer "B.Fab")
		)
		(fp_line
			(start 0.350012 9.150096)
			(end 1.849882 10.649966)
			(stroke
				(width 0.1)
				(type default)
			)
			(layer "B.Fab")
		)
		(fp_line
			(start 1.849882 10.649966)
			(end 4.219956 10.649966)
			(stroke
				(width 0.1)
				(type default)
			)
			(layer "B.Fab")
		)
		(fp_line
			(start 4.219956 10.649966)
			(end 5.72008 9.150096)
			(stroke
				(width 0.1)
				(type default)
			)
			(layer "B.Fab")
		)
		(fp_line
			(start 5.72008 -1.149604)
			(end -8.26008 -1.149604)
			(stroke
				(width 0.1)
				(type default)
			)
			(layer "B.Fab")
		)
		(fp_line
			(start 5.72008 9.150096)
			(end 5.72008 -0.350012)
			(stroke
				(width 0.1)
				(type default)
			)
			(layer "B.Fab")
		)
		(fp_arc
			(start -0.350012 0)
			(mid -0.247504 -0.247514)
			(end 0 -0.350012)
			(stroke
				(width 0.1)
				(type default)
			)
			(layer "B.Fab")
		)
		(fp_arc
			(start 0 -0.350012)
			(mid 0.247496 -0.247499)
			(end 0.350012 0)
			(stroke
				(width 0.1)
				(type default)
			)
			(layer "B.Fab")
		)
		(fp_line
			(start -8.26008 -0.350012)
			(end -8.26008 9.150096)
			(stroke
				(width 0.1)
				(type default)
			)
			(layer "F.Fab")
		)
		(fp_line
			(start -8.26008 9.150096)
			(end -6.759956 10.649966)
			(stroke
				(width 0.1)
				(type default)
			)
			(layer "F.Fab")
		)
		(fp_line
			(start -6.759956 10.649966)
			(end -1.849882 10.649966)
			(stroke
				(width 0.1)
				(type default)
			)
			(layer "F.Fab")
		)
		(fp_line
			(start -1.849882 10.649966)
			(end -0.350012 9.150096)
			(stroke
				(width 0.1)
				(type default)
			)
			(layer "F.Fab")
		)
		(fp_line
			(start -0.350012 9.150096)
			(end -0.350012 0)
			(stroke
				(width 0.1)
				(type default)
			)
			(layer "F.Fab")
		)
		(fp_line
			(start 0.350012 0)
			(end 0.350012 9.150096)
			(stroke
				(width 0.1)
				(type default)
			)
			(layer "F.Fab")
		)
		(fp_line
			(start 0.350012 9.150096)
			(end 1.849882 10.649966)
			(stroke
				(width 0.1)
				(type default)
			)
			(layer "F.Fab")
		)
		(fp_line
			(start 1.849882 10.649966)
			(end 4.219956 10.649966)
			(stroke
				(width 0.1)
				(type default)
			)
			(layer "F.Fab")
		)
		(fp_line
			(start 4.219956 10.649966)
			(end 5.72008 9.150096)
			(stroke
				(width 0.1)
				(type default)
			)
			(layer "F.Fab")
		)
		(fp_line
			(start 5.72008 -1.149604)
			(end -8.26008 -1.149604)
			(stroke
				(width 0.1)
				(type default)
			)
			(layer "F.Fab")
		)
		(fp_line
			(start 5.72008 9.150096)
			(end 5.72008 -0.350012)
			(stroke
				(width 0.1)
				(type default)
			)
			(layer "F.Fab")
		)
		(fp_arc
			(start -0.350012 0)
			(mid -0.247504 -0.247514)
			(end 0 -0.350012)
			(stroke
				(width 0.1)
				(type default)
			)
			(layer "F.Fab")
		)
		(fp_arc
			(start 0 -0.350012)
			(mid 0.247496 -0.247499)
			(end 0.350012 0)
			(stroke
				(width 0.1)
				(type default)
			)
			(layer "F.Fab")
		)
		(pad "P1_P2" smd rect
			(at 2.54 5.999988 180)
			(size 4.3942 6.2992)
			(layers "B.Cu" "B.Mask" "B.Paste")
			(net "P52V_HSC")
		)
		(pad "P3_P4" smd rect
			(at 2.54 5.999988 180)
			(size 4.3942 6.2992)
			(layers "B.Cu" "B.Mask" "B.Paste")
			(net "GND")
		)
		(pad "S1" smd rect
			(at -2.23012 6.649974 180)
			(size 0.8128 5.0038)
			(layers "B.Cu" "B.Mask" "B.Paste")
			(net "RST_SMB_PDB_N")
		)
		(pad "S2" smd rect
			(at -3.50012 6.649974 180)
			(size 0.8128 5.0038)
			(layers "B.Cu" "B.Mask" "B.Paste")
			(net "P52V_FAN_EN_R")
		)
		(pad "S3" smd rect
			(at -4.77012 6.649974 180)
			(size 0.8128 5.0038)
			(layers "B.Cu" "B.Mask" "B.Paste")
			(net "P12V_LED")
		)
		(pad "S4" smd rect
			(at -6.04012 6.649974 180)
			(size 0.8128 5.0038)
			(layers "B.Cu" "B.Mask" "B.Paste")
			(net "P3V3_AUX")
		)
		(pad "S5" smd rect
			(at -6.04012 6.649974 180)
			(size 0.8128 5.0038)
			(layers "B.Cu" "B.Mask" "B.Paste")
			(net "GND")
		)
		(pad "S6" smd rect
			(at -4.77012 6.649974 180)
			(size 0.8128 5.0038)
			(layers "B.Cu" "B.Mask" "B.Paste")
			(net "GND")
		)
		(pad "S7" smd rect
			(at -3.50012 6.649974 180)
			(size 0.8128 5.0038)
			(layers "B.Cu" "B.Mask" "B.Paste")
			(net "SMB_PDBV_FAN_R_SCL")
		)
		(pad "S8" smd rect
			(at -2.23012 6.649974 180)
			(size 0.8128 5.0038)
			(layers "B.Cu" "B.Mask" "B.Paste")
			(net "SMB_PDBV_FAN_R_SDA")
		)
		(zone
			(layer "F.Cu")
			(hatch none 0.5)
			(connect_pads
				(clearance 0)
			)
			(min_thickness 0.25)
			(keepout
				(tracks not_allowed)
				(vias allowed)
				(pads allowed)
				(copperpour not_allowed)
				(footprints allowed)
			)
			(placement
				(enabled no)
				(sheetname "")
			)
			(fill
				(thermal_gap 0.5)
				(thermal_bridge_width 0.5)
				(island_removal_mode 0)
			)
			(polygon
				(pts
					(xy 31.340044 -0.350012) (xy 32.840168 -1.849882) (xy 32.840168 -8.20039) (xy 31.857188 -8.20039)
					(xy 31.857188 -1.85039) (xy 27.462988 -1.85039) (xy 27.462988 -8.20039) (xy 27.412188 -8.20039)
					(xy 27.412188 -1.79959) (xy 27.520392 -1.79959) (xy 28.96997 -0.350012)
				)
			)
		)
		(zone
			(layer "F.Cu")
			(hatch none 0.5)
			(connect_pads
				(clearance 0)
			)
			(min_thickness 0.25)
			(keepout
				(tracks not_allowed)
				(vias allowed)
				(pads allowed)
				(copperpour not_allowed)
				(footprints allowed)
			)
			(placement
				(enabled no)
				(sheetname "")
			)
			(fill
				(thermal_gap 0.5)
				(thermal_bridge_width 0.5)
				(island_removal_mode 0)
			)
			(polygon
				(pts
					(xy 25.270206 -0.350012) (xy 26.770076 -1.849882) (xy 26.770076 -6.902704) (xy 25.296622 -6.902704)
					(xy 25.296622 -6.851904) (xy 25.296622 -1.848104) (xy 24.483568 -1.848104) (xy 24.483568 -6.851904)
					(xy 24.483568 -6.902704) (xy 24.026622 -6.902704) (xy 24.026622 -6.851904) (xy 24.026622 -1.848104)
					(xy 23.213568 -1.848104) (xy 23.213568 -6.851904) (xy 23.213568 -6.902704) (xy 22.756622 -6.902704)
					(xy 22.756622 -6.851904) (xy 22.756622 -1.848104) (xy 21.943568 -1.848104) (xy 21.943568 -6.851904)
					(xy 21.943568 -6.902704) (xy 21.486622 -6.902704) (xy 21.486622 -6.851904) (xy 21.486622 -1.848104)
					(xy 20.673568 -1.848104) (xy 20.673568 -6.851904) (xy 20.673568 -6.902704) (xy 18.860008 -6.902704)
					(xy 18.860008 -1.849882) (xy 20.360132 -0.350012)
				)
			)
		)
		(zone
			(layers "F.Cu" "B.Cu" "In1.Cu" "In2.Cu" "In3.Cu" "In4.Cu")
			(hatch none 0.5)
			(connect_pads
				(clearance 0)
			)
			(min_thickness 0.25)
			(keepout
				(tracks allowed)
				(vias not_allowed)
				(pads allowed)
				(copperpour not_allowed)
				(footprints allowed)
			)
			(placement
				(enabled no)
				(sheetname "")
			)
			(fill
				(thermal_gap 0.5)
				(thermal_bridge_width 0.5)
				(island_removal_mode 0)
			)
			(polygon
				(pts
					(xy 25.347168 -7.105904) (xy 25.347168 -1.797304) (xy 20.622768 -1.797304) (xy 20.622768 -7.105904)
				)
			)
		)
		(zone
			(layers "F.Cu" "B.Cu" "In1.Cu" "In2.Cu" "In3.Cu" "In4.Cu")
			(hatch none 0.5)
			(connect_pads
				(clearance 0)
			)
			(min_thickness 0.25)
			(keepout
				(tracks allowed)
				(vias not_allowed)
				(pads allowed)
				(copperpour not_allowed)
				(footprints allowed)
			)
			(placement
				(enabled no)
				(sheetname "")
			)
			(fill
				(thermal_gap 0.5)
				(thermal_bridge_width 0.5)
				(island_removal_mode 0)
			)
			(polygon
				(pts
					(xy 31.907988 -8.40359) (xy 31.907988 -1.79959) (xy 27.412188 -1.79959) (xy 27.412188 -8.40359)
				)
			)
		)
		(zone
			(layer "B.Cu")
			(hatch none 0.5)
			(connect_pads
				(clearance 0)
			)
			(min_thickness 0.25)
			(keepout
				(tracks not_allowed)
				(vias allowed)
				(pads allowed)
				(copperpour not_allowed)
				(footprints allowed)
			)
			(placement
				(enabled no)
				(sheetname "")
			)
			(fill
				(thermal_gap 0.5)
				(thermal_bridge_width 0.5)
				(island_removal_mode 0)
			)
			(polygon
				(pts
					(xy 31.340044 -0.350012) (xy 32.840168 -1.849882) (xy 32.840168 -8.20039) (xy 31.857188 -8.20039)
					(xy 31.857188 -1.85039) (xy 27.462988 -1.85039) (xy 27.462988 -8.20039) (xy 27.412188 -8.20039)
					(xy 27.412188 -1.79959) (xy 27.520392 -1.79959) (xy 28.96997 -0.350012)
				)
			)
		)
		(zone
			(layer "B.Cu")
			(hatch none 0.5)
			(connect_pads
				(clearance 0)
			)
			(min_thickness 0.25)
			(keepout
				(tracks not_allowed)
				(vias allowed)
				(pads allowed)
				(copperpour not_allowed)
				(footprints allowed)
			)
			(placement
				(enabled no)
				(sheetname "")
			)
			(fill
				(thermal_gap 0.5)
				(thermal_bridge_width 0.5)
				(island_removal_mode 0)
			)
			(polygon
				(pts
					(xy 25.270206 -0.350012) (xy 26.770076 -1.849882) (xy 26.770076 -6.902704) (xy 25.296622 -6.902704)
					(xy 25.296622 -6.851904) (xy 25.296622 -1.848104) (xy 24.483568 -1.848104) (xy 24.483568 -6.851904)
					(xy 24.483568 -6.902704) (xy 24.026622 -6.902704) (xy 24.026622 -6.851904) (xy 24.026622 -1.848104)
					(xy 23.213568 -1.848104) (xy 23.213568 -6.851904) (xy 23.213568 -6.902704) (xy 22.756622 -6.902704)
					(xy 22.756622 -6.851904) (xy 22.756622 -1.848104) (xy 21.943568 -1.848104) (xy 21.943568 -6.851904)
					(xy 21.943568 -6.902704) (xy 21.486622 -6.902704) (xy 21.486622 -6.851904) (xy 21.486622 -1.848104)
					(xy 20.673568 -1.848104) (xy 20.673568 -6.851904) (xy 20.673568 -6.902704) (xy 18.860008 -6.902704)
					(xy 18.860008 -1.849882) (xy 20.360132 -0.350012)
				)
			)
		)
	)
	(footprint ""
		(layer "B.Cu")
		(at 36.449 -64.837056 -90)
		(property "Reference" "PR45"
			(at 0 0 90)
			(layer "B.SilkS")
			(hide yes)
			(effects
				(font
					(size 1.27 1.27)
				)
				(justify mirror)
			)
		)
		(property "Value" ""
			(at 0 0 90)
			(layer "B.Fab")
			(effects
				(font
					(size 1.27 1.27)
				)
				(justify mirror)
			)
		)
		(duplicate_pad_numbers_are_jumpers no)
		(fp_line
			(start -0.7874 0.4064)
			(end 0.7874 0.4064)
			(stroke
				(width 0.1524)
				(type default)
			)
			(layer "B.SilkS")
		)
		(fp_line
			(start 0.7874 0.4064)
			(end 0.7874 -0.4064)
			(stroke
				(width 0.1524)
				(type default)
			)
			(layer "B.SilkS")
		)
		(fp_line
			(start -0.7874 -0.4064)
			(end -0.7874 0.4064)
			(stroke
				(width 0.1524)
				(type default)
			)
			(layer "B.SilkS")
		)
		(fp_line
			(start 0.7874 -0.4064)
			(end -0.7874 -0.4064)
			(stroke
				(width 0.1524)
				(type default)
			)
			(layer "B.SilkS")
		)
		(fp_line
			(start -0.67945 0.3048)
			(end -0.120396 0.3048)
			(stroke
				(width 0.1)
				(type default)
			)
			(layer "B.Fab")
		)
		(fp_line
			(start -0.120396 0.3048)
			(end -0.120396 0.2794)
			(stroke
				(width 0.1)
				(type default)
			)
			(layer "B.Fab")
		)
		(fp_line
			(start 0.12065 0.3048)
			(end 0.67945 0.3048)
			(stroke
				(width 0.1)
				(type default)
			)
			(layer "B.Fab")
		)
		(fp_line
			(start 0.67945 0.3048)
			(end 0.67945 -0.305054)
			(stroke
				(width 0.1)
				(type default)
			)
			(layer "B.Fab")
		)
		(fp_line
			(start -0.120396 0.2794)
			(end 0.12065 0.2794)
			(stroke
				(width 0.1)
				(type default)
			)
			(layer "B.Fab")
		)
		(fp_line
			(start 0.12065 0.2794)
			(end 0.12065 0.3048)
			(stroke
				(width 0.1)
				(type default)
			)
			(layer "B.Fab")
		)
		(fp_line
			(start -0.12065 -0.2794)
			(end -0.12065 -0.3048)
			(stroke
				(width 0.1)
				(type default)
			)
			(layer "B.Fab")
		)
		(fp_line
			(start 0.12065 -0.2794)
			(end -0.12065 -0.2794)
			(stroke
				(width 0.1)
				(type default)
			)
			(layer "B.Fab")
		)
		(fp_line
			(start -0.67945 -0.3048)
			(end -0.67945 0.3048)
			(stroke
				(width 0.1)
				(type default)
			)
			(layer "B.Fab")
		)
		(fp_line
			(start -0.12065 -0.3048)
			(end -0.67945 -0.3048)
			(stroke
				(width 0.1)
				(type default)
			)
			(layer "B.Fab")
		)
		(fp_line
			(start 0.12065 -0.305054)
			(end 0.12065 -0.2794)
			(stroke
				(width 0.1)
				(type default)
			)
			(layer "B.Fab")
		)
		(fp_line
			(start 0.67945 -0.305054)
			(end 0.12065 -0.305054)
			(stroke
				(width 0.1)
				(type default)
			)
			(layer "B.Fab")
		)
		(pad "1" smd circle
			(at 0.40005 0 90)
			(size 0 0)
			(layers "B.Cu" "B.Mask" "B.Paste")
			(net "FAN_3_CLREF")
		)
		(pad "2" smd circle
			(at -0.40005 0 90)
			(size 0 0)
			(layers "B.Cu" "B.Mask" "B.Paste")
			(net "GND")
		)
	)
)
